(kicad_pcb
	(version 20260206)
	(generator "pcbnew")
	(generator_version "10.0")
	(general
		(thickness 1.6)
		(legacy_teardrops no)
	)
	(paper "A4")
	(title_block
		(title "Wiwynn_Tioga_Pass_MB.brd")
		(comment 1 "Tioga Pass / footprints 2136-2140 of 4770")
	)
	(layers
		(0 "F.Cu" signal "TOP")
		(4 "In1.Cu" signal "L2GND")
		(6 "In2.Cu" signal "L3")
		(8 "In3.Cu" signal "L4GND")
		(10 "In4.Cu" signal "L5")
		(12 "In5.Cu" signal "L6GND")
		(14 "In6.Cu" signal "L7VCC")
		(16 "In7.Cu" signal "L8VCC")
		(18 "In8.Cu" signal "L9GND")
		(20 "In9.Cu" signal "L10")
		(22 "In10.Cu" signal "L11GND")
		(24 "In11.Cu" signal "L12")
		(26 "In12.Cu" signal "L13GND")
		(2 "B.Cu" signal "BOTTOM")
		(9 "F.Adhes" user "F.Adhesive")
		(11 "B.Adhes" user "B.Adhesive")
		(13 "F.Paste" user "Package Geometry/Pastemask Top")
		(15 "B.Paste" user "Package Geometry/Pastemask Bottom")
		(5 "F.SilkS" user "Ref Des/Silkscreen Top")
		(7 "B.SilkS" user "Ref Des/Silkscreen Bottom")
		(1 "F.Mask" user "Board Geometry/Soldermask Top")
		(3 "B.Mask" user "Board Geometry/Soldermask Bottom")
		(17 "Dwgs.User" user "User.Drawings")
		(19 "Cmts.User" user "User.Comments")
		(21 "Eco1.User" user "User.Eco1")
		(23 "Eco2.User" user "User.Eco2")
		(25 "Edge.Cuts" user "Board Geometry/Outline")
		(27 "Margin" user)
		(31 "F.CrtYd" user "Package Geometry/Place Bound Top")
		(29 "B.CrtYd" user "Package Geometry/Place Bound Bottom")
		(35 "F.Fab" user "Ref Des/Assembly Top")
		(33 "B.Fab" user "Ref Des/Assembly Bottom")
	)
	(footprint ""
		(layer "F.Cu")
		(at 385.318 -87.3125 180)
		(property "Reference" "R7D12"
			(at 0 0 180)
			(layer "F.SilkS")
			(hide yes)
			(effects
				(font
					(size 1.27 1.27)
				)
			)
		)
		(property "Value" ""
			(at 0 0 180)
			(layer "F.Fab")
			(effects
				(font
					(size 1.27 1.27)
				)
			)
		)
		(duplicate_pad_numbers_are_jumpers no)
		(fp_poly
			(pts
				(xy -0.2794 -0.1016) (xy 0.2794 -0.1016) (xy 0.2794 0.9906) (xy -0.2794 0.9906)
			)
			(stroke
				(width 0)
				(type default)
			)
			(fill no)
			(layer "F.CrtYd")
		)
		(fp_line
			(start 0.2794 0.9906)
			(end 0.2794 -0.1016)
			(stroke
				(width 0.1)
				(type default)
			)
			(layer "F.Fab")
		)
		(fp_line
			(start 0.2794 -0.1016)
			(end -0.2794 -0.1016)
			(stroke
				(width 0.1)
				(type default)
			)
			(layer "F.Fab")
		)
		(fp_line
			(start -0.2794 0.9906)
			(end 0.2794 0.9906)
			(stroke
				(width 0.1)
				(type default)
			)
			(layer "F.Fab")
		)
		(fp_line
			(start -0.2794 -0.1016)
			(end -0.2794 0.9906)
			(stroke
				(width 0.1)
				(type default)
			)
			(layer "F.Fab")
		)
		(pad "1" smd rect
			(at 0 0 180)
			(size 0.508 0.508)
			(layers "F.Cu" "F.Mask" "F.Paste")
			(net "P3V3_STBY")
		)
		(pad "2" smd rect
			(at 0 0.889 180)
			(size 0.508 0.508)
			(layers "F.Cu" "F.Mask" "F.Paste")
			(net "FM_OCP_MEZZA_PRES")
		)
		(zone
			(layer "F.Cu")
			(hatch none 0.5)
			(connect_pads
				(clearance 0)
			)
			(min_thickness 0.25)
			(keepout
				(tracks not_allowed)
				(vias allowed)
				(pads allowed)
				(copperpour not_allowed)
				(footprints allowed)
			)
			(placement
				(enabled no)
				(sheetname "")
			)
			(fill
				(thermal_gap 0.5)
				(thermal_bridge_width 0.5)
				(island_removal_mode 0)
			)
			(polygon
				(pts
					(xy 385.572 -87.9475) (xy 385.064 -87.9475) (xy 385.064 -87.5665) (xy 385.572 -87.5665)
				)
			)
		)
		(zone
			(layer "F.Cu")
			(hatch none 0.5)
			(connect_pads
				(clearance 0)
			)
			(min_thickness 0.25)
			(keepout
				(tracks allowed)
				(vias not_allowed)
				(pads allowed)
				(copperpour not_allowed)
				(footprints allowed)
			)
			(placement
				(enabled no)
				(sheetname "")
			)
			(fill
				(thermal_gap 0.5)
				(thermal_bridge_width 0.5)
				(island_removal_mode 0)
			)
			(polygon
				(pts
					(xy 385.572 -87.5665) (xy 385.064 -87.5665) (xy 385.064 -87.9475) (xy 385.572 -87.9475)
				)
			)
		)
	)
	(footprint ""
		(layer "F.Cu")
		(at 13.8938 -30.353 90)
		(property "Reference" "C1F11"
			(at 0 0 90)
			(layer "F.SilkS")
			(hide yes)
			(effects
				(font
					(size 1.27 1.27)
				)
			)
		)
		(property "Value" ""
			(at 0 0 90)
			(layer "F.Fab")
			(effects
				(font
					(size 1.27 1.27)
				)
			)
		)
		(duplicate_pad_numbers_are_jumpers no)
		(fp_rect
			(start -0.3048 -0.1016)
			(end 0.3048 0.9906)
			(stroke
				(width 0)
				(type default)
			)
			(fill no)
			(layer "F.CrtYd")
		)
		(fp_line
			(start 0.3048 -0.1016)
			(end -0.3048 -0.1016)
			(stroke
				(width 0.1)
				(type default)
			)
			(layer "F.Fab")
		)
		(fp_line
			(start -0.3048 -0.1016)
			(end -0.3048 0.9906)
			(stroke
				(width 0.1)
				(type default)
			)
			(layer "F.Fab")
		)
		(fp_line
			(start 0.3048 0.9906)
			(end 0.3048 -0.1016)
			(stroke
				(width 0.1)
				(type default)
			)
			(layer "F.Fab")
		)
		(fp_line
			(start -0.3048 0.9906)
			(end 0.3048 0.9906)
			(stroke
				(width 0.1)
				(type default)
			)
			(layer "F.Fab")
		)
		(pad "1" smd rect
			(at 0 0 90)
			(size 0.508 0.508)
			(layers "F.Cu" "F.Mask" "F.Paste")
			(net "P3E_CPU1_PE3_MP_C_TXP<4>")
		)
		(pad "2" smd rect
			(at 0 0.889 90)
			(size 0.508 0.508)
			(layers "F.Cu" "F.Mask" "F.Paste")
			(net "P3E_CPU1_PE3_MP_TXP<4>")
		)
		(zone
			(layer "F.Cu")
			(hatch none 0.5)
			(connect_pads
				(clearance 0)
			)
			(min_thickness 0.25)
			(keepout
				(tracks allowed)
				(vias not_allowed)
				(pads allowed)
				(copperpour not_allowed)
				(footprints allowed)
			)
			(placement
				(enabled no)
				(sheetname "")
			)
			(fill
				(thermal_gap 0.5)
				(thermal_bridge_width 0.5)
				(island_removal_mode 0)
			)
			(polygon
				(pts
					(xy 14.1478 -30.099) (xy 14.5288 -30.099) (xy 14.5288 -30.607) (xy 14.1478 -30.607)
				)
			)
		)
		(zone
			(layer "F.Cu")
			(hatch none 0.5)
			(connect_pads
				(clearance 0)
			)
			(min_thickness 0.25)
			(keepout
				(tracks not_allowed)
				(vias allowed)
				(pads allowed)
				(copperpour not_allowed)
				(footprints allowed)
			)
			(placement
				(enabled no)
				(sheetname "")
			)
			(fill
				(thermal_gap 0.5)
				(thermal_bridge_width 0.5)
				(island_removal_mode 0)
			)
			(polygon
				(pts
					(xy 14.1478 -30.099) (xy 14.5288 -30.099) (xy 14.5288 -30.607) (xy 14.1478 -30.607)
				)
			)
		)
	)
	(footprint ""
		(layer "F.Cu")
		(at 431.766472 -45.05452 -90)
		(property "Reference" "R9F62"
			(at 0 0 270)
			(layer "F.SilkS")
			(hide yes)
			(effects
				(font
					(size 1.27 1.27)
				)
			)
		)
		(property "Value" ""
			(at 0 0 270)
			(layer "F.Fab")
			(effects
				(font
					(size 1.27 1.27)
				)
			)
		)
		(duplicate_pad_numbers_are_jumpers no)
		(fp_poly
			(pts
				(xy -0.2794 -0.1016) (xy 0.2794 -0.1016) (xy 0.2794 0.9906) (xy -0.2794 0.9906)
			)
			(stroke
				(width 0)
				(type default)
			)
			(fill no)
			(layer "F.CrtYd")
		)
		(fp_line
			(start -0.2794 0.9906)
			(end 0.2794 0.9906)
			(stroke
				(width 0.1)
				(type default)
			)
			(layer "F.Fab")
		)
		(fp_line
			(start 0.2794 0.9906)
			(end 0.2794 -0.1016)
			(stroke
				(width 0.1)
				(type default)
			)
			(layer "F.Fab")
		)
		(fp_line
			(start -0.2794 -0.1016)
			(end -0.2794 0.9906)
			(stroke
				(width 0.1)
				(type default)
			)
			(layer "F.Fab")
		)
		(fp_line
			(start 0.2794 -0.1016)
			(end -0.2794 -0.1016)
			(stroke
				(width 0.1)
				(type default)
			)
			(layer "F.Fab")
		)
		(pad "1" smd rect
			(at 0 0 270)
			(size 0.508 0.508)
			(layers "F.Cu" "F.Mask" "F.Paste")
			(net "CLK_24M_BMC_CLKIN_R")
		)
		(pad "2" smd rect
			(at 0 0.889 270)
			(size 0.508 0.508)
			(layers "F.Cu" "F.Mask" "F.Paste")
			(net "CLK_24M_25M_BMC_CLKIN")
		)
		(zone
			(layer "F.Cu")
			(hatch none 0.5)
			(connect_pads
				(clearance 0)
			)
			(min_thickness 0.25)
			(keepout
				(tracks not_allowed)
				(vias allowed)
				(pads allowed)
				(copperpour not_allowed)
				(footprints allowed)
			)
			(placement
				(enabled no)
				(sheetname "")
			)
			(fill
				(thermal_gap 0.5)
				(thermal_bridge_width 0.5)
				(island_removal_mode 0)
			)
			(polygon
				(pts
					(xy 431.131472 -45.30852) (xy 431.131472 -44.80052) (xy 431.512472 -44.80052) (xy 431.512472 -45.30852)
				)
			)
		)
		(zone
			(layer "F.Cu")
			(hatch none 0.5)
			(connect_pads
				(clearance 0)
			)
			(min_thickness 0.25)
			(keepout
				(tracks allowed)
				(vias not_allowed)
				(pads allowed)
				(copperpour not_allowed)
				(footprints allowed)
			)
			(placement
				(enabled no)
				(sheetname "")
			)
			(fill
				(thermal_gap 0.5)
				(thermal_bridge_width 0.5)
				(island_removal_mode 0)
			)
			(polygon
				(pts
					(xy 431.512472 -45.30852) (xy 431.512472 -44.80052) (xy 431.131472 -44.80052) (xy 431.131472 -45.30852)
				)
			)
		)
	)
	(footprint ""
		(layer "F.Cu")
		(at 184.260998 2.679192 -90)
		(property "Reference" "C4G24"
			(at 0 0 270)
			(layer "F.SilkS")
			(hide yes)
			(effects
				(font
					(size 1.27 1.27)
				)
			)
		)
		(property "Value" ""
			(at 0 0 270)
			(layer "F.Fab")
			(effects
				(font
					(size 1.27 1.27)
				)
			)
		)
		(duplicate_pad_numbers_are_jumpers no)
		(fp_rect
			(start 0.7239 1.9939)
			(end -0.7239 -0.2159)
			(stroke
				(width 0)
				(type default)
			)
			(fill no)
			(layer "F.CrtYd")
		)
		(fp_line
			(start -0.7239 1.9939)
			(end 0.7239 1.9939)
			(stroke
				(width 0.1)
				(type default)
			)
			(layer "F.Fab")
		)
		(fp_line
			(start 0.7239 1.9939)
			(end 0.7239 -0.2159)
			(stroke
				(width 0.1)
				(type default)
			)
			(layer "F.Fab")
		)
		(fp_line
			(start -0.7239 -0.2159)
			(end -0.7239 1.9939)
			(stroke
				(width 0.1)
				(type default)
			)
			(layer "F.Fab")
		)
		(fp_line
			(start 0.7239 -0.2159)
			(end -0.7239 -0.2159)
			(stroke
				(width 0.1)
				(type default)
			)
			(layer "F.Fab")
		)
		(pad "1" smd rect
			(at 0 0 270)
			(size 1.27 1.016)
			(layers "F.Cu" "F.Mask" "F.Paste")
			(net "PVTT_ABC")
		)
		(pad "2" smd rect
			(at 0 1.778 270)
			(size 1.27 1.016)
			(layers "F.Cu" "F.Mask" "F.Paste")
			(net "GND")
		)
		(zone
			(layer "F.Cu")
			(hatch none 0.5)
			(connect_pads
				(clearance 0)
			)
			(min_thickness 0.25)
			(keepout
				(tracks not_allowed)
				(vias allowed)
				(pads allowed)
				(copperpour not_allowed)
				(footprints allowed)
			)
			(placement
				(enabled no)
				(sheetname "")
			)
			(fill
				(thermal_gap 0.5)
				(thermal_bridge_width 0.5)
				(island_removal_mode 0)
			)
			(polygon
				(pts
					(xy 182.990998 3.314192) (xy 183.752998 3.314192) (xy 183.752998 2.044192) (xy 182.990998 2.044192)
				)
			)
		)
	)
	(footprint ""
		(layer "F.Cu")
		(at 99.438968 -79.6036 180)
		(property "Reference" "C2D14"
			(at 0 0 180)
			(layer "F.SilkS")
			(hide yes)
			(effects
				(font
					(size 1.27 1.27)
				)
			)
		)
		(property "Value" ""
			(at 0 0 180)
			(layer "F.Fab")
			(effects
				(font
					(size 1.27 1.27)
				)
			)
		)
		(duplicate_pad_numbers_are_jumpers no)
		(fp_poly
			(pts
				(xy -0.4953 -0.2032) (xy 0.4953 -0.2032) (xy 0.4953 1.6002) (xy -0.4953 1.6002)
			)
			(stroke
				(width 0)
				(type default)
			)
			(fill no)
			(layer "F.CrtYd")
		)
		(fp_line
			(start 0.4953 1.6002)
			(end -0.4953 1.6002)
			(stroke
				(width 0.1)
				(type default)
			)
			(layer "F.Fab")
		)
		(fp_line
			(start 0.4953 -0.2032)
			(end 0.4953 1.6002)
			(stroke
				(width 0.1)
				(type default)
			)
			(layer "F.Fab")
		)
		(fp_line
			(start -0.4953 1.6002)
			(end -0.4953 -0.2032)
			(stroke
				(width 0.1)
				(type default)
			)
			(layer "F.Fab")
		)
		(fp_line
			(start -0.4953 -0.2032)
			(end 0.4953 -0.2032)
			(stroke
				(width 0.1)
				(type default)
			)
			(layer "F.Fab")
		)
		(pad "1" smd rect
			(at 0 0 180)
			(size 0.762 0.889)
			(layers "F.Cu" "F.Mask" "F.Paste")
			(net "PVCCIN_CPU1")
		)
		(pad "2" smd rect
			(at 0 1.397 180)
			(size 0.762 0.889)
			(layers "F.Cu" "F.Mask" "F.Paste")
			(net "GND")
		)
		(zone
			(layer "F.Cu")
			(hatch none 0.5)
			(connect_pads
				(clearance 0)
			)
			(min_thickness 0.25)
			(keepout
				(tracks not_allowed)
				(vias allowed)
				(pads allowed)
				(copperpour not_allowed)
				(footprints allowed)
			)
			(placement
				(enabled no)
				(sheetname "")
			)
			(fill
				(thermal_gap 0.5)
				(thermal_bridge_width 0.5)
				(island_removal_mode 0)
			)
			(polygon
				(pts
					(xy 99.819968 -80.0481) (xy 99.057968 -80.0481) (xy 99.057968 -80.5561) (xy 99.819968 -80.5561)
				)
			)
		)
	)
)
